# S9S_MB_2U (Grand Teton) — schematic netlist excerpt (pin names and nets, part order shuffled) for the footprints in the layout excerpt that follows; sources: Cadence DE-HDL packaged netlist, KiCad conversion of 03242023_DA0F0TMBIJ0_F0T_Motherboard_J_brd_V01_OCP.brd

C413  Q_CAP  22UF 4V 20% X6S  pkg C0402  page 74 : A = PVCCFA_EHV_FIVRA_CPU0 ; B = GND
R969  Q_RES  240 1% CHIP  pkg 0402LF  page 236 : A = PVNN_TERM_CPU0 ; B = SMB_S3M_CPU0_R_SCL

(kicad_pcb
	(version 20260206)
	(generator "pcbnew")
	(generator_version "10.0")
	(general
		(thickness 1.6)
		(legacy_teardrops no)
	)
	(paper "A4")
	(title_block
		(title "03242023_DA0F0TMBIJ0_F0T_Motherboard_J_brd_V01_OCP.brd")
		(comment 1 "Grand Teton / footprints 1997-1998 of 6105")
	)
	(layers
		(0 "F.Cu" signal "TOP")
		(4 "In1.Cu" signal "GND")
		(6 "In2.Cu" signal "IN1")
		(8 "In3.Cu" signal "GND1")
		(10 "In4.Cu" signal "IN2")
		(12 "In5.Cu" signal "GND2")
		(14 "In6.Cu" signal "IN3")
		(16 "In7.Cu" signal "GND3")
		(18 "In8.Cu" signal "VCC")
		(20 "In9.Cu" signal "VCC1")
		(22 "In10.Cu" signal "GND4")
		(24 "In11.Cu" signal "IN4")
		(26 "In12.Cu" signal "GND5")
		(28 "In13.Cu" signal "IN5")
		(30 "In14.Cu" signal "GND6")
		(32 "In15.Cu" signal "IN6")
		(34 "In16.Cu" signal "GND7")
		(2 "B.Cu" signal "BOTTOM")
		(9 "F.Adhes" user "F.Adhesive")
		(11 "B.Adhes" user "B.Adhesive")
		(13 "F.Paste" user "Package Geometry/Pastemask Top")
		(15 "B.Paste" user "Package Geometry/Pastemask Bottom")
		(5 "F.SilkS" user "Ref Des/Silkscreen Top")
		(7 "B.SilkS" user "Ref Des/Silkscreen Bottom")
		(1 "F.Mask" user "Board Geometry/Soldermask Top")
		(3 "B.Mask" user "Board Geometry/Soldermask Bottom")
		(17 "Dwgs.User" user "User.Drawings")
		(19 "Cmts.User" user "User.Comments")
		(21 "Eco1.User" user "User.Eco1")
		(23 "Eco2.User" user "User.Eco2")
		(25 "Edge.Cuts" user "Board Geometry/Outline")
		(27 "Margin" user)
		(31 "F.CrtYd" user "Package Geometry/Place Bound Top")
		(29 "B.CrtYd" user "Package Geometry/Place Bound Bottom")
		(35 "F.Fab" user "Ref Des/Assembly Top")
		(33 "B.Fab" user "Ref Des/Assembly Bottom")
	)
	(footprint ""
		(layer "F.Cu")
		(at 394.141198 -161.07791 180)
		(property "Reference" "R969"
			(at 0 0 180)
			(layer "F.SilkS")
			(hide yes)
			(effects
				(font
					(size 1.27 1.27)
				)
			)
		)
		(property "Value" ""
			(at 0 0 180)
			(layer "F.Fab")
			(effects
				(font
					(size 1.27 1.27)
				)
			)
		)
		(duplicate_pad_numbers_are_jumpers no)
		(fp_line
			(start 0.7874 0.4064)
			(end -0.7874 0.4064)
			(stroke
				(width 0.1524)
				(type default)
			)
			(layer "F.SilkS")
		)
		(fp_line
			(start 0.7874 -0.4064)
			(end 0.7874 0.4064)
			(stroke
				(width 0.1524)
				(type default)
			)
			(layer "F.SilkS")
		)
		(fp_line
			(start -0.7874 0.4064)
			(end -0.7874 -0.4064)
			(stroke
				(width 0.1524)
				(type default)
			)
			(layer "F.SilkS")
		)
		(fp_line
			(start -0.7874 -0.4064)
			(end 0.7874 -0.4064)
			(stroke
				(width 0.1524)
				(type default)
			)
			(layer "F.SilkS")
		)
		(fp_line
			(start 0.67945 0.3048)
			(end 0.120396 0.3048)
			(stroke
				(width 0.1)
				(type default)
			)
			(layer "F.Fab")
		)
		(fp_line
			(start 0.67945 -0.3048)
			(end 0.67945 0.3048)
			(stroke
				(width 0.1)
				(type default)
			)
			(layer "F.Fab")
		)
		(fp_line
			(start 0.12065 -0.2794)
			(end 0.12065 -0.3048)
			(stroke
				(width 0.1)
				(type default)
			)
			(layer "F.Fab")
		)
		(fp_line
			(start 0.12065 -0.3048)
			(end 0.67945 -0.3048)
			(stroke
				(width 0.1)
				(type default)
			)
			(layer "F.Fab")
		)
		(fp_line
			(start 0.120396 0.3048)
			(end 0.120396 0.2794)
			(stroke
				(width 0.1)
				(type default)
			)
			(layer "F.Fab")
		)
		(fp_line
			(start 0.120396 0.2794)
			(end -0.12065 0.2794)
			(stroke
				(width 0.1)
				(type default)
			)
			(layer "F.Fab")
		)
		(fp_line
			(start -0.12065 0.3048)
			(end -0.67945 0.3048)
			(stroke
				(width 0.1)
				(type default)
			)
			(layer "F.Fab")
		)
		(fp_line
			(start -0.12065 0.2794)
			(end -0.12065 0.3048)
			(stroke
				(width 0.1)
				(type default)
			)
			(layer "F.Fab")
		)
		(fp_line
			(start -0.12065 -0.2794)
			(end 0.12065 -0.2794)
			(stroke
				(width 0.1)
				(type default)
			)
			(layer "F.Fab")
		)
		(fp_line
			(start -0.12065 -0.305054)
			(end -0.12065 -0.2794)
			(stroke
				(width 0.1)
				(type default)
			)
			(layer "F.Fab")
		)
		(fp_line
			(start -0.67945 0.3048)
			(end -0.67945 -0.305054)
			(stroke
				(width 0.1)
				(type default)
			)
			(layer "F.Fab")
		)
		(fp_line
			(start -0.67945 -0.305054)
			(end -0.12065 -0.305054)
			(stroke
				(width 0.1)
				(type default)
			)
			(layer "F.Fab")
		)
		(pad "1" smd circle
			(at -0.40005 0 180)
			(size 0 0)
			(layers "F.Cu" "F.Mask" "F.Paste")
			(net "PVNN_TERM_CPU0")
		)
		(pad "2" smd circle
			(at 0.40005 0 180)
			(size 0 0)
			(layers "F.Cu" "F.Mask" "F.Paste")
			(net "SMB_S3M_CPU0_R_SCL")
		)
	)
	(footprint ""
		(layer "F.Cu")
		(at 355.227128 -260.364986 -90)
		(property "Reference" "C413"
			(at 0 0 270)
			(layer "F.SilkS")
			(hide yes)
			(effects
				(font
					(size 1.27 1.27)
				)
			)
		)
		(property "Value" ""
			(at 0 0 270)
			(layer "F.Fab")
			(effects
				(font
					(size 1.27 1.27)
				)
			)
		)
		(duplicate_pad_numbers_are_jumpers no)
		(fp_line
			(start -0.7874 0.4064)
			(end -0.7874 -0.4064)
			(stroke
				(width 0.1524)
				(type default)
			)
			(layer "F.SilkS")
		)
		(fp_line
			(start 0.7874 0.4064)
			(end -0.7874 0.4064)
			(stroke
				(width 0.1524)
				(type default)
			)
			(layer "F.SilkS")
		)
		(fp_line
			(start -0.7874 -0.4064)
			(end 0.7874 -0.4064)
			(stroke
				(width 0.1524)
				(type default)
			)
			(layer "F.SilkS")
		)
		(fp_line
			(start 0.7874 -0.4064)
			(end 0.7874 0.4064)
			(stroke
				(width 0.1524)
				(type default)
			)
			(layer "F.SilkS")
		)
		(fp_line
			(start -0.67945 0.3048)
			(end -0.67945 -0.305054)
			(stroke
				(width 0.1)
				(type default)
			)
			(layer "F.Fab")
		)
		(fp_line
			(start -0.12065 0.3048)
			(end -0.67945 0.3048)
			(stroke
				(width 0.1)
				(type default)
			)
			(layer "F.Fab")
		)
		(fp_line
			(start 0.120396 0.3048)
			(end 0.120396 0.2794)
			(stroke
				(width 0.1)
				(type default)
			)
			(layer "F.Fab")
		)
		(fp_line
			(start 0.67945 0.3048)
			(end 0.120396 0.3048)
			(stroke
				(width 0.1)
				(type default)
			)
			(layer "F.Fab")
		)
		(fp_line
			(start -0.12065 0.2794)
			(end -0.12065 0.3048)
			(stroke
				(width 0.1)
				(type default)
			)
			(layer "F.Fab")
		)
		(fp_line
			(start 0.120396 0.2794)
			(end -0.12065 0.2794)
			(stroke
				(width 0.1)
				(type default)
			)
			(layer "F.Fab")
		)
		(fp_line
			(start -0.12065 -0.2794)
			(end 0.12065 -0.2794)
			(stroke
				(width 0.1)
				(type default)
			)
			(layer "F.Fab")
		)
		(fp_line
			(start 0.12065 -0.2794)
			(end 0.12065 -0.3048)
			(stroke
				(width 0.1)
				(type default)
			)
			(layer "F.Fab")
		)
		(fp_line
			(start 0.12065 -0.3048)
			(end 0.67945 -0.3048)
			(stroke
				(width 0.1)
				(type default)
			)
			(layer "F.Fab")
		)
		(fp_line
			(start 0.67945 -0.3048)
			(end 0.67945 0.3048)
			(stroke
				(width 0.1)
				(type default)
			)
			(layer "F.Fab")
		)
		(fp_line
			(start -0.67945 -0.305054)
			(end -0.12065 -0.305054)
			(stroke
				(width 0.1)
				(type default)
			)
			(layer "F.Fab")
		)
		(fp_line
			(start -0.12065 -0.305054)
			(end -0.12065 -0.2794)
			(stroke
				(width 0.1)
				(type default)
			)
			(layer "F.Fab")
		)
		(pad "1" smd circle
			(at -0.40005 0 270)
			(size 0 0)
			(layers "F.Cu" "F.Mask" "F.Paste")
			(net "PVCCFA_EHV_FIVRA_CPU0")
		)
		(pad "2" smd circle
			(at 0.40005 0 270)
			(size 0 0)
			(layers "F.Cu" "F.Mask" "F.Paste")
			(net "GND")
		)
	)
)
